# T6G (Grand Teton) — schematic netlist excerpt (pin names and nets, part order shuffled) for the footprints in the layout excerpt that follows; sources: Cadence DE-HDL packaged netlist, KiCad conversion of 04192023_DAF0TMB3IC0_F0TG_MB_C_brd_V02_OCP.brd

J15  SCONN288_DDR506112002KQ  IO  pkg DDR288S_1-1VXC  page 87
  VIN_BULK0  = P12V_MEM_CPU0
  RFU0  = NC
  VIN_MGMT  = P3V3_AUX
  HSCL  = I3C_SPD_DDRB_CPU0_SCL
  HSDA  = I3C_SPD_DDRB_CPU0_SDA
  VSS0  = GND
  DQ0_A  = M_B_CPU0_SA_DQ<0>
  VSS1  = GND
  DQ1_A  = M_B_CPU0_SA_DQ<1>
  VSS2  = GND
  DQS0_A_T  = M_B_CPU0_SA_DQS_DP<0>
  DQS0_A_C  = M_B_CPU0_SA_DQS_DN<0>
  VSS3  = GND
  DQ4_A  = M_B_CPU0_SA_DQ<4>
  VSS4  = GND
  DQ5_A  = M_B_CPU0_SA_DQ<5>
  VSS5  = GND
  DQ8_A  = M_B_CPU0_SA_DQ<8>
  VSS6  = GND
  DQ9_A  = M_B_CPU0_SA_DQ<9>
  VSS7  = GND
  DQS1_A_T  = M_B_CPU0_SA_DQS_DP<1>
  DQS1_A_C  = M_B_CPU0_SA_DQS_DN<1>
  VSS8  = GND
  DQ12_A  = M_B_CPU0_SA_DQ<12>
  VSS9  = GND
  DQ13_A  = M_B_CPU0_SA_DQ<13>
  VSS10  = GND
  DQ16_A  = M_B_CPU0_SA_DQ<16>
  VSS11  = GND
  DQ17_A  = M_B_CPU0_SA_DQ<17>
  VSS12  = GND
  DQS2_A_T  = M_B_CPU0_SA_DQS_DP<2>
  DQS2_A_C  = M_B_CPU0_SA_DQS_DN<2>
  VSS13  = GND
  DQ20_A  = M_B_CPU0_SA_DQ<20>
  VSS14  = GND
  DQ21_A  = M_B_CPU0_SA_DQ<21>
  VSS15  = GND
  DQ24_A  = M_B_CPU0_SA_DQ<24>
  VSS16  = GND
  DQ25_A  = M_B_CPU0_SA_DQ<25>
  VSS17  = GND
  DQS3_A_T  = M_B_CPU0_SA_DQS_DP<3>
  DQS3_A_C  = M_B_CPU0_SA_DQS_DN<3>
  VSS18  = GND
  DQ28_A  = M_B_CPU0_SA_DQ<28>
  VSS19  = GND
  DQ29_A  = M_B_CPU0_SA_DQ<29>
  VSS20  = GND
  CB0_A  = M_B_CPU0_SA_CB<0>
  VSS21  = GND
  CB1_A  = M_B_CPU0_SA_CB<1>
  VSS22  = GND
  DQS4_A_T  = M_B_CPU0_SA_DQS_DP<4>
  DQS4_A_C  = M_B_CPU0_SA_DQS_DN<4>
  VSS23  = GND
  CB4_A  = M_B_CPU0_SA_CB<4>
  VSS24  = GND
  CB5_A  = M_B_CPU0_SA_CB<5>
  VSS25  = GND
  ALERT_N  = M_B_CPU0_ALERT_N
  VSS26  = GND
  CS0_A_N  = M_B_CPU0_SA_CS_N<0>
  VSS27  = GND
  CA0_A  = M_B_CPU0_SA_CA<0>
  VSS28  = GND
  CA2_A  = M_B_CPU0_SA_CA<2>
  VSS29  = GND
  CA4_A  = M_B_CPU0_SA_CA<4>
  VSS30  = GND
  CA6_A  = M_B_CPU0_SA_CA<6>
  VSS31  = GND
  PAR_A  = M_B_CPU0_SA_PAR
  VSS32  = GND
  CA0_B  = M_B_CPU0_SB_CA<0>
  VSS33  = GND
  CA2_B  = M_B_CPU0_SB_CA<2>
  VSS34  = GND
  CA4_B  = M_B_CPU0_SB_CA<4>
  VSS35  = GND
  CA6_B  = M_B_CPU0_SB_CA<6>
  VSS36  = GND
  CS0_B_N  = M_B_CPU0_SB_CS_N<0>
  VSS37  = GND
  \lbd||rsp_a_n\  = M_B_CPU0_SA_RSP<0>
  \lbs||rsp_b_n\  = M_B_CPU0_SB_RSP<0>
  VSS38  = GND
  CB4_B  = M_B_CPU0_SB_CB<4>
  VSS39  = GND
  CB5_B  = M_B_CPU0_SB_CB<5>
  VSS40  = GND
  \dqs9_b_t||tdqs9_b_t||dbi4_b_n\  = M_B_CPU0_SB_DQS_DP<9>
  \dqs9_b_c||tdqs9_b_c\  = M_B_CPU0_SB_DQS_DN<9>
  VSS41  = GND
  CB0_B  = M_B_CPU0_SB_CB<0>
  VSS42  = GND
  CB1_B  = M_B_CPU0_SB_CB<1>
  VSS43  = GND
  DQ0_B  = M_B_CPU0_SB_DQ<0>
  VSS44  = GND
  DQ1_B  = M_B_CPU0_SB_DQ<1>
  VSS45  = GND
  DQS0_B_T  = M_B_CPU0_SB_DQS_DP<0>
  DQS0_B_C  = M_B_CPU0_SB_DQS_DN<0>
  VSS46  = GND
  DQ4_B  = M_B_CPU0_SB_DQ<4>
  VSS47  = GND
  DQ5_B  = M_B_CPU0_SB_DQ<5>
  VSS48  = GND
  DQ8_B  = M_B_CPU0_SB_DQ<8>
  VSS49  = GND
  DQ9_B  = M_B_CPU0_SB_DQ<9>
  VSS50  = GND
  DQS1_B_T  = M_B_CPU0_SB_DQS_DP<1>
  DQS1_B_C  = M_B_CPU0_SB_DQS_DN<1>
  VSS51  = GND
  DQ12_B  = M_B_CPU0_SB_DQ<12>
  VSS52  = GND
  DQ13_B  = M_B_CPU0_SB_DQ<13>
  VSS53  = GND
  DQ16_B  = M_B_CPU0_SB_DQ<16>
  VSS54  = GND
  DQ17_B  = M_B_CPU0_SB_DQ<17>
  VSS55  = GND
  DQS2_B_T  = M_B_CPU0_SB_DQS_DP<2>
  DQS2_B_C  = M_B_CPU0_SB_DQS_DN<2>
  VSS56  = GND
  DQ20_B  = M_B_CPU0_SB_DQ<20>
  VSS57  = GND
  DQ21_B  = M_B_CPU0_SB_DQ<21>
  VSS58  = GND
  DQ24_B  = M_B_CPU0_SB_DQ<24>
  VSS59  = GND
  DQ25_B  = M_B_CPU0_SB_DQ<25>
  VSS60  = GND
  DQS3_B_T  = M_B_CPU0_SB_DQS_DP<3>
  DQS3_B_C  = M_B_CPU0_SB_DQS_DN<3>
  VSS61  = GND
  DQ28_B  = M_B_CPU0_SB_DQ<28>
  VSS62  = GND
  DQ29_B  = M_B_CPU0_SB_DQ<29>
  VSS63  = GND
  RFU1  = NC
  VIN_BULK1  = P12V_MEM_CPU0
  VIN_BULK2  = P12V_MEM_CPU0
  \pwr_good||fail_n\  = PWRGD_CHB_CPU0_DIMM
  HAS  = PD_CHB_CPU0_DIMM_SAA
  RFU2  = NC
  RFU3  = NC
  VSS64  = GND
  DQ2_A  = M_B_CPU0_SA_DQ<2>
  VSS65  = GND
  DQ3_A  = M_B_CPU0_SA_DQ<3>
  VSS66  = GND
  \dqs5_a_c||tdqs5_a_c||dqs5_a_t||tdqs5_a_t\  = M_B_CPU0_SA_DQS_DN<5>
  \dqs5_a_t||tdqs5_a_t\  = M_B_CPU0_SA_DQS_DP<5>
  VSS67  = GND
  DQ6_A  = M_B_CPU0_SA_DQ<6>
  VSS68  = GND
  DQ7_A  = M_B_CPU0_SA_DQ<7>
  VSS69  = GND
  DQ10_A  = M_B_CPU0_SA_DQ<10>
  VSS70  = GND
  DQ11_A  = M_B_CPU0_SA_DQ<11>
  VSS71  = GND
  \dqs6_a_c||tdqs6_a_c||dqs6_a_t||tdqs6_a_t\  = M_B_CPU0_SA_DQS_DN<6>
  \dqs6_a_t||tdqs6_a_t\  = M_B_CPU0_SA_DQS_DP<6>
  VSS72  = GND
  DQ14_A  = M_B_CPU0_SA_DQ<14>
  VSS73  = GND
  DQ15_A  = M_B_CPU0_SA_DQ<15>
  VSS74  = GND
  DQ18_A  = M_B_CPU0_SA_DQ<18>
  VSS75  = GND
  DQ19_A  = M_B_CPU0_SA_DQ<19>
  VSS76  = GND
  \dqs7_a_c||tdqs7_a_c\  = M_B_CPU0_SA_DQS_DN<7>
  \dqs7_a_t||tdqs7_a_t\  = M_B_CPU0_SA_DQS_DP<7>
  VSS77  = GND
  DQ22_A  = M_B_CPU0_SA_DQ<22>
  VSS78  = GND
  DQ23_A  = M_B_CPU0_SA_DQ<23>
  VSS79  = GND
  DQ26_A  = M_B_CPU0_SA_DQ<26>
  VSS80  = GND
  DQ27_A  = M_B_CPU0_SA_DQ<27>
  VSS81  = GND
  \dqs8_a_c||tdqs8_a_c\  = M_B_CPU0_SA_DQS_DN<8>
  \dqs8_a_t||tdqs8_a_t\  = M_B_CPU0_SA_DQS_DP<8>
  VSS82  = GND
  DQ30_A  = M_B_CPU0_SA_DQ<30>
  VSS83  = GND
  DQ31_A  = M_B_CPU0_SA_DQ<31>
  VSS84  = GND
  CB2_A  = M_B_CPU0_SA_CB<2>
  VSS85  = GND
  CB3_A  = M_B_CPU0_SA_CB<3>
  VSS86  = GND
  \dqs9_a_c||tdqs9_a_c\  = M_B_CPU0_SA_DQS_DN<9>
  \dqs9_a_t||tdqs9_a_t\  = M_B_CPU0_SA_DQS_DP<9>
  VSS87  = GND
  CB6_A  = M_B_CPU0_SA_CB<6>
  VSS88  = GND
  CB7_A  = M_B_CPU0_SA_CB<7>
  VSS89  = GND
  RESET_N  = M_B_CPU0_RESET_N
  VSS90  = GND
  CS1_A_N  = M_B_CPU0_SA_CS_N<1>
  VSS91  = GND
  CA1_A  = M_B_CPU0_SA_CA<1>
  VSS92  = GND
  CA3_A  = M_B_CPU0_SA_CA<3>
  VSS93  = GND
  CA5_A  = M_B_CPU0_SA_CA<5>
  VSS94  = GND
  CK_T  = M_B_CPU0_CLK_DP<0>
  CK_C  = M_B_CPU0_CLK_DN<0>
  VSS95  = GND
  RFU4  = NC
  CA1_B  = M_B_CPU0_SB_CA<1>
  VSS96  = GND
  CA3_B  = M_B_CPU0_SB_CA<3>
  VSS97  = GND
  CA5_B  = M_B_CPU0_SB_CA<5>
  VSS98  = GND
  PAR_B  = M_B_CPU0_SB_PAR
  VSS99  = GND
  CS1_B_N  = M_B_CPU0_SB_CS_N<1>
  VSS100  = GND
  RFU5  = NC
  RFU6  = NC
  VSS101  = GND
  CB6_B  = M_B_CPU0_SB_CB<6>
  VSS102  = GND
  CB7_B  = M_B_CPU0_SB_CB<7>
  VSS103  = GND
  DQS4_B_C  = M_B_CPU0_SB_DQS_DN<4>
  DQS4_B_T  = M_B_CPU0_SB_DQS_DP<4>
  VSS104  = GND
  CB2_B  = M_B_CPU0_SB_CB<2>
  VSS105  = GND
  CB3_B  = M_B_CPU0_SB_CB<3>
  VSS106  = GND
  DQ2_B  = M_B_CPU0_SB_DQ<2>
  VSS107  = GND
  DQ3_B  = M_B_CPU0_SB_DQ<3>
  VSS108  = GND
  \dqs5_b_c||tdqs5_b_c\  = M_B_CPU0_SB_DQS_DN<5>
  \dqs5_b_t||tdqs5_b_t\  = M_B_CPU0_SB_DQS_DP<5>
  VSS109  = GND
  DQ6_B  = M_B_CPU0_SB_DQ<6>
  VSS110  = GND
  DQ7_B  = M_B_CPU0_SB_DQ<7>
  VSS111  = GND
  DQ10_B  = M_B_CPU0_SB_DQ<10>
  VSS112  = GND
  DQ11_B  = M_B_CPU0_SB_DQ<11>
  VSS113  = GND
  \dqs6_b_c||tdqs6_b_c\  = M_B_CPU0_SB_DQS_DN<6>
  \dqs6_b_t||tdqs6_b_t\  = M_B_CPU0_SB_DQS_DP<6>
  VSS114  = GND
  DQ14_B  = M_B_CPU0_SB_DQ<14>
  VSS115  = GND
  DQ15_B  = M_B_CPU0_SB_DQ<15>
  VSS116  = GND
  DQ18_B  = M_B_CPU0_SB_DQ<18>
  VSS117  = GND
  DQ19_B  = M_B_CPU0_SB_DQ<19>
  VSS118  = GND
  \dqs7_b_c||tdqs7_b_c\  = M_B_CPU0_SB_DQS_DN<7>
  \dqs7_b_t||tdqs7_b_t\  = M_B_CPU0_SB_DQS_DP<7>
  VSS119  = GND
  DQ22_B  = M_B_CPU0_SB_DQ<22>
  VSS120  = GND
  DQ23_B  = M_B_CPU0_SB_DQ<23>
  VSS121  = GND
  DQ26_B  = M_B_CPU0_SB_DQ<26>
  VSS122  = GND
  DQ27_B  = M_B_CPU0_SB_DQ<27>
  VSS123  = GND
  \dqs8_b_c||tdqs8_b_c\  = M_B_CPU0_SB_DQS_DN<8>
  \dqs8_b_t||tdqs8_b_t\  = M_B_CPU0_SB_DQS_DP<8>
  VSS124  = GND
  DQ30_B  = M_B_CPU0_SB_DQ<30>
  VSS125  = GND
  DQ31_B  = M_B_CPU0_SB_DQ<31>
  VSS126  = GND
  G1  = GND
  G2  = GND
  G3  = GND

(kicad_pcb
	(version 20260206)
	(generator "pcbnew")
	(generator_version "10.0")
	(general
		(thickness 1.6)
		(legacy_teardrops no)
	)
	(paper "A4")
	(title_block
		(title "04192023_DAF0TMB3IC0_F0TG_MB_C_brd_V02_OCP.brd")
		(comment 1 "Grand Teton / footprint 1120 of 8354 (J15), pads 277-291 of 291")
	)
	(layers
		(0 "F.Cu" signal "TOP")
		(4 "In1.Cu" signal "GND")
		(6 "In2.Cu" signal "IN1")
		(8 "In3.Cu" signal "GND1")
		(10 "In4.Cu" signal "IN2")
		(12 "In5.Cu" signal "GND2")
		(14 "In6.Cu" signal "IN3")
		(16 "In7.Cu" signal "GND3")
		(18 "In8.Cu" signal "VCC")
		(20 "In9.Cu" signal "VCC1")
		(22 "In10.Cu" signal "GND4")
		(24 "In11.Cu" signal "IN4")
		(26 "In12.Cu" signal "GND5")
		(28 "In13.Cu" signal "IN5")
		(30 "In14.Cu" signal "GND6")
		(32 "In15.Cu" signal "IN6")
		(34 "In16.Cu" signal "GND7")
		(2 "B.Cu" signal "BOTTOM")
		(9 "F.Adhes" user "F.Adhesive")
		(11 "B.Adhes" user "B.Adhesive")
		(13 "F.Paste" user "Package Geometry/Pastemask Top")
		(15 "B.Paste" user "Package Geometry/Pastemask Bottom")
		(5 "F.SilkS" user "Ref Des/Silkscreen Top")
		(7 "B.SilkS" user "Ref Des/Silkscreen Bottom")
		(1 "F.Mask" user "Board Geometry/Soldermask Top")
		(3 "B.Mask" user "Board Geometry/Soldermask Bottom")
		(17 "Dwgs.User" user "User.Drawings")
		(19 "Cmts.User" user "User.Comments")
		(21 "Eco1.User" user "User.Eco1")
		(23 "Eco2.User" user "User.Eco2")
		(25 "Edge.Cuts" user "Board Geometry/Outline")
		(27 "Margin" user)
		(31 "F.CrtYd" user "Package Geometry/Place Bound Top")
		(29 "B.CrtYd" user "Package Geometry/Place Bound Bottom")
		(35 "F.Fab" user "Ref Des/Assembly Top")
		(33 "B.Fab" user "Ref Des/Assembly Bottom")
	)
	(footprint ""
		(layer "F.Cu")
		(at 297.774106 -255.560068 180)
		(property "Reference" "J15"
			(at -2.2098 -81.984088 0)
			(unlocked yes)
			(layer "F.SilkS")
			(effects
				(font
					(size 0.7874 0.5842)
					(thickness 0.1524)
				)
			)
		)
		(property "Value" ""
			(at 0 0 180)
			(layer "F.Fab")
			(effects
				(font
					(size 1.27 1.27)
				)
			)
		)
		(duplicate_pad_numbers_are_jumpers no)
		(pad "277" smd rect
			(at 2.050034 53.975 90)
			(size 0.519938 1.4986)
			(layers "F.Cu" "F.Mask" "F.Paste")
			(net "GND")
		)
		(pad "278" smd rect
			(at 2.050034 54.824884 90)
			(size 0.519938 1.4986)
			(layers "F.Cu" "F.Mask" "F.Paste")
			(net "M_B_CPU0_SB_DQ<26>")
		)
		(pad "279" smd rect
			(at 2.050034 55.675022 90)
			(size 0.519938 1.4986)
			(layers "F.Cu" "F.Mask" "F.Paste")
			(net "GND")
		)
		(pad "280" smd rect
			(at 2.050034 56.524906 90)
			(size 0.519938 1.4986)
			(layers "F.Cu" "F.Mask" "F.Paste")
			(net "M_B_CPU0_SB_DQ<27>")
		)
		(pad "281" smd rect
			(at 2.050034 57.375044 90)
			(size 0.519938 1.4986)
			(layers "F.Cu" "F.Mask" "F.Paste")
			(net "GND")
		)
		(pad "282" smd rect
			(at 2.050034 58.224928 90)
			(size 0.519938 1.4986)
			(layers "F.Cu" "F.Mask" "F.Paste")
			(net "M_B_CPU0_SB_DQS_DN<8>")
		)
		(pad "283" smd rect
			(at 2.050034 59.075066 90)
			(size 0.519938 1.4986)
			(layers "F.Cu" "F.Mask" "F.Paste")
			(net "M_B_CPU0_SB_DQS_DP<8>")
		)
		(pad "284" smd rect
			(at 2.050034 59.92495 90)
			(size 0.519938 1.4986)
			(layers "F.Cu" "F.Mask" "F.Paste")
			(net "GND")
		)
		(pad "285" smd rect
			(at 2.050034 60.775088 90)
			(size 0.519938 1.4986)
			(layers "F.Cu" "F.Mask" "F.Paste")
			(net "M_B_CPU0_SB_DQ<30>")
		)
		(pad "286" smd rect
			(at 2.050034 61.624972 90)
			(size 0.519938 1.4986)
			(layers "F.Cu" "F.Mask" "F.Paste")
			(net "GND")
		)
		(pad "287" smd rect
			(at 2.050034 62.47511 90)
			(size 0.519938 1.4986)
			(layers "F.Cu" "F.Mask" "F.Paste")
			(net "M_B_CPU0_SB_DQ<31>")
		)
		(pad "288" smd rect
			(at 2.050034 63.324994 90)
			(size 0.519938 1.4986)
			(layers "F.Cu" "F.Mask" "F.Paste")
			(net "GND")
		)
		(pad "G1" thru_hole oval
			(at 0 -68.97497 90)
			(size 1.7272 3.4798)
			(drill oval 1.2192 2.4638)
			(layers "*.Cu" "*.Mask")
			(remove_unused_layers no)
			(net "GND")
			(clearance 0.127)
			(thermal_gap 0.127)
		)
		(pad "G2" thru_hole oval
			(at 0 3.875024 90)
			(size 1.7272 3.4798)
			(drill oval 1.2192 2.4638)
			(layers "*.Cu" "*.Mask")
			(remove_unused_layers no)
			(net "GND")
			(clearance 0.127)
			(thermal_gap 0.127)
		)
		(pad "G3" thru_hole oval
			(at 0 68.97497 90)
			(size 1.7272 3.4798)
			(drill oval 1.2192 2.4638)
			(layers "*.Cu" "*.Mask")
			(remove_unused_layers no)
			(net "GND")
			(clearance 0.127)
			(thermal_gap 0.127)
		)
	)
)
